#ISCELL
  mstr_misc dns *
  *
#ISCELL
  pure_quanta quanta_title_block_c *
  *
#ISCELL
  standard offpage *
  page174_i1
#ISCELL
  pure_quanta_power universal_gnd *
  page174_i16
#CELL
  pure_quanta q_res *
  page174_i17
#CELL
  pure_quanta q_res *
  page174_i18
#ISCELL
  pure_quanta_power universal_gnd *
  page174_i2
#CELL
  pure_quanta q_cap *
  page174_i20
#CELL
  pure_quanta q_cap *
  page174_i21
#CELL
  pure_quanta q_cap *
  page174_i22
#ISCELL
  pure_quanta_power universal_gnd *
  page174_i23
#CELL
  pure_quanta q_cap *
  page174_i25
#CELL
  pure_quanta q_cap *
  page174_i26
#ISCELL
  pure_quanta_power vcc_core *
  page174_i27
#ISCELL
  pure_quanta_power universal_gnd *
  page174_i28
#CELL
  pure_quanta q_cap *
  page174_i29
#ISCELL
  pure_quanta_power universal_gnd *
  page174_i3
#ISCELL
  pure_quanta_power vcc_core *
  page174_i30
#CELL
  pure_quanta q_inductor4p_14 *
  page174_i31
#CELL
  pure_quanta q_cap *
  page174_i32
#CELL
  pure_quanta q_cap *
  page174_i37
#CELL
  pure_quanta q_cap *
  page174_i38
#ISCELL
  pure_quanta_power universal_gnd *
  page174_i39
#ISCELL
  standard offpage *
  page174_i4
#ISCELL
  pure_quanta_power universal_gnd *
  page174_i40
#CELL
  pure_quanta q_res *
  page174_i41
#CELL
  pure_quanta q_cap *
  page174_i42
#CELL
  pure_quanta isl99390frztr5935 *
  page174_i44
#CELL
  pure_quanta q_cap *
  page174_i46
#CELL
  pure_quanta q_res *
  page174_i47
#ISCELL
  pure_quanta_power universal_gnd *
  page174_i48
#ISCELL
  pure_quanta_power vcc_core *
  page174_i49
#ISCELL
  standard offpage *
  page174_i5
#CELL
  pure_quanta q_cap *
  page174_i50
#CELL
  pure_quanta q_inductor *
  page174_i51
#ISCELL
  pure_quanta_power universal_gnd *
  page174_i52
#ISCELL
  standard offpage *
  page174_i53
#CELL
  pure_quanta q_cap *
  page174_i6
#CELL
  pure_quanta q_res *
  page174_i7
#ISCELL
  standard offpage *
  page174_i8
